(kicad_pcb
	(version 20260206)
	(generator "pcbnew")
	(generator_version "10.0")
	(general
		(thickness 1.6)
		(legacy_teardrops no)
	)
	(paper "A4")
	(title_block
		(title "peb — Lightning_PEB_BRD.brd")
		(comment 1 "Lightning (Wiwynn / Facebook NVMe JBOF) / footprints 2247-2254 of 2563")
	)
	(layers
		(0 "F.Cu" signal "TOP")
		(4 "In1.Cu" signal "L2GND")
		(6 "In2.Cu" signal "L3")
		(8 "In3.Cu" signal "L4VCC")
		(10 "In4.Cu" signal "L5VCC")
		(12 "In5.Cu" signal "L6")
		(14 "In6.Cu" signal "L7GND")
		(2 "B.Cu" signal "BOTTOM")
		(9 "F.Adhes" user "F.Adhesive")
		(11 "B.Adhes" user "B.Adhesive")
		(13 "F.Paste" user "Package Geometry/Pastemask Top")
		(15 "B.Paste" user "Package Geometry/Pastemask Bottom")
		(5 "F.SilkS" user "Ref Des/Silkscreen Top")
		(7 "B.SilkS" user "Ref Des/Silkscreen Bottom")
		(1 "F.Mask" user "Board Geometry/Soldermask Top")
		(3 "B.Mask" user "Board Geometry/Soldermask Bottom")
		(17 "Dwgs.User" user "User.Drawings")
		(19 "Cmts.User" user "User.Comments")
		(21 "Eco1.User" user "User.Eco1")
		(23 "Eco2.User" user "User.Eco2")
		(25 "Edge.Cuts" user "Board Geometry/Outline")
		(27 "Margin" user)
		(31 "F.CrtYd" user "Package Geometry/Place Bound Top")
		(29 "B.CrtYd" user "Package Geometry/Place Bound Bottom")
		(35 "F.Fab" user "Ref Des/Assembly Top")
		(33 "B.Fab" user "Ref Des/Assembly Bottom")
	)
	(footprint ""
		(layer "B.Cu")
		(at 20.955 -138.811 -90)
		(property "Reference" "R659"
			(at 0 0 90)
			(layer "B.SilkS")
			(hide yes)
			(effects
				(font
					(size 1.27 1.27)
				)
				(justify mirror)
			)
		)
		(property "Value" "0R2J-2-GP"
			(at -0.064008 -3.993896 270)
			(unlocked yes)
			(layer "B.Fab")
			(hide yes)
			(effects
				(font
					(size 1.016 1.016)
					(thickness 0.1524)
				)
				(justify mirror)
			)
		)
		(property "Device Type" "R402H16"
			(at -0.064008 -5.517896 270)
			(unlocked yes)
			(layer "B.Fab")
			(hide yes)
			(effects
				(font
					(size 1.016 1.016)
					(thickness 0.1524)
				)
				(justify mirror)
			)
		)
		(duplicate_pad_numbers_are_jumpers no)
		(fp_line
			(start -0.508 -0.9398)
			(end 0.508 -0.9398)
			(stroke
				(width 0.1524)
				(type default)
			)
			(layer "B.SilkS")
		)
		(fp_line
			(start 0.508 -0.9398)
			(end 0.508 0.9398)
			(stroke
				(width 0.1524)
				(type default)
			)
			(layer "B.SilkS")
		)
		(fp_rect
			(start 0.508 0.9398)
			(end -0.508 -0.9398)
			(stroke
				(width 0)
				(type default)
			)
			(fill no)
			(layer "B.CrtYd")
		)
		(fp_rect
			(start 0.508 0.9398)
			(end -0.508 -0.9398)
			(stroke
				(width 0)
				(type default)
			)
			(fill no)
			(layer "B.Fab")
		)
		(pad "1" smd custom
			(at 0 -0.4445 90)
			(size 0.1397 0.1397)
			(layers "B.Cu" "B.Mask" "B.Paste")
			(net "GPIOR3_R")
			(options
				(clearance outline)
				(anchor circle)
			)
			(primitives
				(gr_poly
					(pts
						(arc
							(start -0.1778 0.2794)
							(mid -0.249642 0.249642)
							(end -0.2794 0.1778)
						)
						(arc
							(start -0.2794 -0.1778)
							(mid -0.249642 -0.249642)
							(end -0.1778 -0.2794)
						)
						(arc
							(start 0.1778 -0.2794)
							(mid 0.249642 -0.249642)
							(end 0.2794 -0.1778)
						)
						(arc
							(start 0.2794 0.1778)
							(mid 0.249642 0.249642)
							(end 0.1778 0.2794)
						)
					)
					(width 0)
					(fill yes)
				)
			)
		)
		(pad "2" smd custom
			(at 0 0.4445 90)
			(size 0.1397 0.1397)
			(layers "B.Cu" "B.Mask" "B.Paste")
			(net "BP_PRSNT_N")
			(options
				(clearance outline)
				(anchor circle)
			)
			(primitives
				(gr_poly
					(pts
						(arc
							(start -0.1778 0.2794)
							(mid -0.249642 0.249642)
							(end -0.2794 0.1778)
						)
						(arc
							(start -0.2794 -0.1778)
							(mid -0.249642 -0.249642)
							(end -0.1778 -0.2794)
						)
						(arc
							(start 0.1778 -0.2794)
							(mid 0.249642 -0.249642)
							(end 0.2794 -0.1778)
						)
						(arc
							(start 0.2794 0.1778)
							(mid 0.249642 0.249642)
							(end 0.1778 0.2794)
						)
					)
					(width 0)
					(fill yes)
				)
			)
		)
	)
	(footprint ""
		(layer "B.Cu")
		(at 252.5776 -40.005 -90)
		(property "Reference" "C590"
			(at 0 0 90)
			(layer "B.SilkS")
			(hide yes)
			(effects
				(font
					(size 1.27 1.27)
				)
				(justify mirror)
			)
		)
		(property "Value" "SCD1U16V1KX-1-GP"
			(at 2.8321 -1.7399 270)
			(unlocked yes)
			(layer "B.Fab")
			(hide yes)
			(effects
				(font
					(size 1.016 1.016)
					(thickness 0.1524)
				)
				(justify mirror)
			)
		)
		(property "Device Type" "C0201H13"
			(at 2.8321 -3.2639 270)
			(unlocked yes)
			(layer "B.Fab")
			(hide yes)
			(effects
				(font
					(size 1.016 1.016)
					(thickness 0.1524)
				)
				(justify mirror)
			)
		)
		(duplicate_pad_numbers_are_jumpers no)
		(fp_rect
			(start 0.2794 0.6477)
			(end -0.2794 -0.6477)
			(stroke
				(width 0)
				(type default)
			)
			(fill no)
			(layer "B.CrtYd")
		)
		(fp_rect
			(start 0.2794 0.6477)
			(end -0.2794 -0.6477)
			(stroke
				(width 0)
				(type default)
			)
			(fill no)
			(layer "B.Fab")
		)
		(pad "1" smd custom
			(at 0 -0.2794 90)
			(size 0.0762 0.0762)
			(layers "B.Cu" "B.Mask" "B.Paste")
			(net "DUT_AVD_PCIE")
			(options
				(clearance outline)
				(anchor circle)
			)
			(primitives
				(gr_poly
					(pts
						(arc
							(start 0.1524 0.127)
							(mid 0.137521 0.162921)
							(end 0.1016 0.1778)
						)
						(arc
							(start -0.1016 0.1778)
							(mid -0.137521 0.162921)
							(end -0.1524 0.127)
						)
						(arc
							(start -0.1524 -0.127)
							(mid -0.137521 -0.162921)
							(end -0.1016 -0.1778)
						)
						(arc
							(start 0.1016 -0.1778)
							(mid 0.137521 -0.162921)
							(end 0.1524 -0.127)
						)
					)
					(width 0)
					(fill yes)
				)
			)
		)
		(pad "2" smd custom
			(at 0 0.2794 90)
			(size 0.0762 0.0762)
			(layers "B.Cu" "B.Mask" "B.Paste")
			(net "GND")
			(options
				(clearance outline)
				(anchor circle)
			)
			(primitives
				(gr_poly
					(pts
						(arc
							(start 0.1524 0.127)
							(mid 0.137521 0.162921)
							(end 0.1016 0.1778)
						)
						(arc
							(start -0.1016 0.1778)
							(mid -0.137521 0.162921)
							(end -0.1524 0.127)
						)
						(arc
							(start -0.1524 -0.127)
							(mid -0.137521 -0.162921)
							(end -0.1016 -0.1778)
						)
						(arc
							(start 0.1016 -0.1778)
							(mid 0.137521 -0.162921)
							(end 0.1524 -0.127)
						)
					)
					(width 0)
					(fill yes)
				)
			)
		)
	)
	(footprint ""
		(layer "B.Cu")
		(at 20.955 -130.683 90)
		(property "Reference" "R345"
			(at 0 0 90)
			(layer "B.SilkS")
			(hide yes)
			(effects
				(font
					(size 1.27 1.27)
				)
				(justify mirror)
			)
		)
		(property "Value" "3K3R2F-2-GP"
			(at -0.064008 -3.993896 90)
			(unlocked yes)
			(layer "B.Fab")
			(hide yes)
			(effects
				(font
					(size 1.016 1.016)
					(thickness 0.1524)
				)
				(justify mirror)
			)
		)
		(property "Device Type" "R402H16"
			(at -0.064008 -5.517896 90)
			(unlocked yes)
			(layer "B.Fab")
			(hide yes)
			(effects
				(font
					(size 1.016 1.016)
					(thickness 0.1524)
				)
				(justify mirror)
			)
		)
		(duplicate_pad_numbers_are_jumpers no)
		(fp_line
			(start 0.508 -0.9398)
			(end 0.508 0.9398)
			(stroke
				(width 0.1524)
				(type default)
			)
			(layer "B.SilkS")
		)
		(fp_line
			(start -0.508 -0.9398)
			(end 0.508 -0.9398)
			(stroke
				(width 0.1524)
				(type default)
			)
			(layer "B.SilkS")
		)
		(fp_rect
			(start 0.508 0.9398)
			(end -0.508 -0.9398)
			(stroke
				(width 0)
				(type default)
			)
			(fill no)
			(layer "B.CrtYd")
		)
		(fp_rect
			(start 0.508 0.9398)
			(end -0.508 -0.9398)
			(stroke
				(width 0)
				(type default)
			)
			(fill no)
			(layer "B.Fab")
		)
		(pad "1" smd custom
			(at 0 -0.4445 270)
			(size 0.1397 0.1397)
			(layers "B.Cu" "B.Mask" "B.Paste")
			(net "P3V3_STBY")
			(options
				(clearance outline)
				(anchor circle)
			)
			(primitives
				(gr_poly
					(pts
						(arc
							(start -0.1778 0.2794)
							(mid -0.249642 0.249642)
							(end -0.2794 0.1778)
						)
						(arc
							(start -0.2794 -0.1778)
							(mid -0.249642 -0.249642)
							(end -0.1778 -0.2794)
						)
						(arc
							(start 0.1778 -0.2794)
							(mid 0.249642 -0.249642)
							(end 0.2794 -0.1778)
						)
						(arc
							(start 0.2794 0.1778)
							(mid 0.249642 0.249642)
							(end 0.1778 0.2794)
						)
					)
					(width 0)
					(fill yes)
				)
			)
		)
		(pad "2" smd custom
			(at 0 0.4445 270)
			(size 0.1397 0.1397)
			(layers "B.Cu" "B.Mask" "B.Paste")
			(net "ROMA17")
			(options
				(clearance outline)
				(anchor circle)
			)
			(primitives
				(gr_poly
					(pts
						(arc
							(start -0.1778 0.2794)
							(mid -0.249642 0.249642)
							(end -0.2794 0.1778)
						)
						(arc
							(start -0.2794 -0.1778)
							(mid -0.249642 -0.249642)
							(end -0.1778 -0.2794)
						)
						(arc
							(start 0.1778 -0.2794)
							(mid 0.249642 -0.249642)
							(end 0.2794 -0.1778)
						)
						(arc
							(start 0.2794 0.1778)
							(mid 0.249642 0.249642)
							(end 0.1778 0.2794)
						)
					)
					(width 0)
					(fill yes)
				)
			)
		)
	)
	(footprint ""
		(layer "B.Cu")
		(at 181.70652 -6.04012 180)
		(property "Reference" "R329"
			(at 0 0 0)
			(layer "B.SilkS")
			(hide yes)
			(effects
				(font
					(size 1.27 1.27)
				)
				(justify mirror)
			)
		)
		(property "Value" "0R2J-2-GP"
			(at -0.064008 -3.993896 180)
			(unlocked yes)
			(layer "B.Fab")
			(hide yes)
			(effects
				(font
					(size 1.016 1.016)
					(thickness 0.1524)
				)
				(justify mirror)
			)
		)
		(property "Device Type" "R402H16"
			(at -0.064008 -5.517896 180)
			(unlocked yes)
			(layer "B.Fab")
			(hide yes)
			(effects
				(font
					(size 1.016 1.016)
					(thickness 0.1524)
				)
				(justify mirror)
			)
		)
		(duplicate_pad_numbers_are_jumpers no)
		(fp_line
			(start 0.508 -0.9398)
			(end 0.508 0.9398)
			(stroke
				(width 0.1524)
				(type default)
			)
			(layer "B.SilkS")
		)
		(fp_line
			(start -0.508 -0.9398)
			(end 0.508 -0.9398)
			(stroke
				(width 0.1524)
				(type default)
			)
			(layer "B.SilkS")
		)
		(fp_rect
			(start 0.508 0.9398)
			(end -0.508 -0.9398)
			(stroke
				(width 0)
				(type default)
			)
			(fill no)
			(layer "B.CrtYd")
		)
		(fp_rect
			(start 0.508 0.9398)
			(end -0.508 -0.9398)
			(stroke
				(width 0)
				(type default)
			)
			(fill no)
			(layer "B.Fab")
		)
		(pad "1" smd custom
			(at 0 -0.4445)
			(size 0.1397 0.1397)
			(layers "B.Cu" "B.Mask" "B.Paste")
			(net "CLK_P_1_R")
			(options
				(clearance outline)
				(anchor circle)
			)
			(primitives
				(gr_poly
					(pts
						(arc
							(start -0.1778 0.2794)
							(mid -0.249642 0.249642)
							(end -0.2794 0.1778)
						)
						(arc
							(start -0.2794 -0.1778)
							(mid -0.249642 -0.249642)
							(end -0.1778 -0.2794)
						)
						(arc
							(start 0.1778 -0.2794)
							(mid 0.249642 -0.249642)
							(end 0.2794 -0.1778)
						)
						(arc
							(start 0.2794 0.1778)
							(mid 0.249642 0.249642)
							(end 0.1778 0.2794)
						)
					)
					(width 0)
					(fill yes)
				)
			)
		)
		(pad "2" smd custom
			(at 0 0.4445)
			(size 0.1397 0.1397)
			(layers "B.Cu" "B.Mask" "B.Paste")
			(net "PCIE_REFCLK_H2_P_R")
			(options
				(clearance outline)
				(anchor circle)
			)
			(primitives
				(gr_poly
					(pts
						(arc
							(start -0.1778 0.2794)
							(mid -0.249642 0.249642)
							(end -0.2794 0.1778)
						)
						(arc
							(start -0.2794 -0.1778)
							(mid -0.249642 -0.249642)
							(end -0.1778 -0.2794)
						)
						(arc
							(start 0.1778 -0.2794)
							(mid 0.249642 -0.249642)
							(end 0.2794 -0.1778)
						)
						(arc
							(start 0.2794 0.1778)
							(mid 0.249642 0.249642)
							(end 0.1778 0.2794)
						)
					)
					(width 0)
					(fill yes)
				)
			)
		)
	)
	(footprint ""
		(layer "B.Cu")
		(at 46.3042 -104.0384 180)
		(property "Reference" "R408"
			(at 0 0 0)
			(layer "B.SilkS")
			(hide yes)
			(effects
				(font
					(size 1.27 1.27)
				)
				(justify mirror)
			)
		)
		(property "Value" "4K7R2F-GP"
			(at -0.064008 -3.993896 180)
			(unlocked yes)
			(layer "B.Fab")
			(hide yes)
			(effects
				(font
					(size 1.016 1.016)
					(thickness 0.1524)
				)
				(justify mirror)
			)
		)
		(property "Device Type" "R402H16"
			(at -0.064008 -5.517896 180)
			(unlocked yes)
			(layer "B.Fab")
			(hide yes)
			(effects
				(font
					(size 1.016 1.016)
					(thickness 0.1524)
				)
				(justify mirror)
			)
		)
		(duplicate_pad_numbers_are_jumpers no)
		(fp_line
			(start 0.508 -0.9398)
			(end 0.508 0.9398)
			(stroke
				(width 0.1524)
				(type default)
			)
			(layer "B.SilkS")
		)
		(fp_line
			(start -0.508 -0.9398)
			(end 0.508 -0.9398)
			(stroke
				(width 0.1524)
				(type default)
			)
			(layer "B.SilkS")
		)
		(fp_rect
			(start 0.508 0.9398)
			(end -0.508 -0.9398)
			(stroke
				(width 0)
				(type default)
			)
			(fill no)
			(layer "B.CrtYd")
		)
		(fp_rect
			(start 0.508 0.9398)
			(end -0.508 -0.9398)
			(stroke
				(width 0)
				(type default)
			)
			(fill no)
			(layer "B.Fab")
		)
		(pad "1" smd custom
			(at 0 -0.4445)
			(size 0.1397 0.1397)
			(layers "B.Cu" "B.Mask" "B.Paste")
			(net "P3V3_STBY")
			(options
				(clearance outline)
				(anchor circle)
			)
			(primitives
				(gr_poly
					(pts
						(arc
							(start -0.1778 0.2794)
							(mid -0.249642 0.249642)
							(end -0.2794 0.1778)
						)
						(arc
							(start -0.2794 -0.1778)
							(mid -0.249642 -0.249642)
							(end -0.1778 -0.2794)
						)
						(arc
							(start 0.1778 -0.2794)
							(mid 0.249642 -0.249642)
							(end 0.2794 -0.1778)
						)
						(arc
							(start 0.2794 0.1778)
							(mid 0.249642 0.249642)
							(end 0.1778 0.2794)
						)
					)
					(width 0)
					(fill yes)
				)
			)
		)
		(pad "2" smd custom
			(at 0 0.4445)
			(size 0.1397 0.1397)
			(layers "B.Cu" "B.Mask" "B.Paste")
			(net "I2C8_LS_G1")
			(options
				(clearance outline)
				(anchor circle)
			)
			(primitives
				(gr_poly
					(pts
						(arc
							(start -0.1778 0.2794)
							(mid -0.249642 0.249642)
							(end -0.2794 0.1778)
						)
						(arc
							(start -0.2794 -0.1778)
							(mid -0.249642 -0.249642)
							(end -0.1778 -0.2794)
						)
						(arc
							(start 0.1778 -0.2794)
							(mid 0.249642 -0.249642)
							(end 0.2794 -0.1778)
						)
						(arc
							(start 0.2794 0.1778)
							(mid 0.249642 0.249642)
							(end 0.1778 0.2794)
						)
					)
					(width 0)
					(fill yes)
				)
			)
		)
	)
	(footprint ""
		(layer "B.Cu")
		(at 24.139144 -134.687564 90)
		(property "Reference" "R341"
			(at 0 0 90)
			(layer "B.SilkS")
			(hide yes)
			(effects
				(font
					(size 1.27 1.27)
				)
				(justify mirror)
			)
		)
		(property "Value" "3K3R2F-2-GP"
			(at -0.064008 -3.993896 90)
			(unlocked yes)
			(layer "B.Fab")
			(hide yes)
			(effects
				(font
					(size 1.016 1.016)
					(thickness 0.1524)
				)
				(justify mirror)
			)
		)
		(property "Device Type" "R402H16"
			(at -0.064008 -5.517896 90)
			(unlocked yes)
			(layer "B.Fab")
			(hide yes)
			(effects
				(font
					(size 1.016 1.016)
					(thickness 0.1524)
				)
				(justify mirror)
			)
		)
		(duplicate_pad_numbers_are_jumpers no)
		(fp_line
			(start 0.508 -0.9398)
			(end 0.508 0.9398)
			(stroke
				(width 0.1524)
				(type default)
			)
			(layer "B.SilkS")
		)
		(fp_line
			(start -0.508 -0.9398)
			(end 0.508 -0.9398)
			(stroke
				(width 0.1524)
				(type default)
			)
			(layer "B.SilkS")
		)
		(fp_rect
			(start 0.508 0.9398)
			(end -0.508 -0.9398)
			(stroke
				(width 0)
				(type default)
			)
			(fill no)
			(layer "B.CrtYd")
		)
		(fp_rect
			(start 0.508 0.9398)
			(end -0.508 -0.9398)
			(stroke
				(width 0)
				(type default)
			)
			(fill no)
			(layer "B.Fab")
		)
		(pad "1" smd custom
			(at 0 -0.4445 270)
			(size 0.1397 0.1397)
			(layers "B.Cu" "B.Mask" "B.Paste")
			(net "P3V3_STBY")
			(options
				(clearance outline)
				(anchor circle)
			)
			(primitives
				(gr_poly
					(pts
						(arc
							(start -0.1778 0.2794)
							(mid -0.249642 0.249642)
							(end -0.2794 0.1778)
						)
						(arc
							(start -0.2794 -0.1778)
							(mid -0.249642 -0.249642)
							(end -0.1778 -0.2794)
						)
						(arc
							(start 0.1778 -0.2794)
							(mid 0.249642 -0.249642)
							(end 0.2794 -0.1778)
						)
						(arc
							(start 0.2794 0.1778)
							(mid 0.249642 0.249642)
							(end 0.1778 0.2794)
						)
					)
					(width 0)
					(fill yes)
				)
			)
		)
		(pad "2" smd custom
			(at 0 0.4445 270)
			(size 0.1397 0.1397)
			(layers "B.Cu" "B.Mask" "B.Paste")
			(net "ROMA16")
			(options
				(clearance outline)
				(anchor circle)
			)
			(primitives
				(gr_poly
					(pts
						(arc
							(start -0.1778 0.2794)
							(mid -0.249642 0.249642)
							(end -0.2794 0.1778)
						)
						(arc
							(start -0.2794 -0.1778)
							(mid -0.249642 -0.249642)
							(end -0.1778 -0.2794)
						)
						(arc
							(start 0.1778 -0.2794)
							(mid 0.249642 -0.249642)
							(end 0.2794 -0.1778)
						)
						(arc
							(start 0.2794 0.1778)
							(mid 0.249642 0.249642)
							(end 0.1778 0.2794)
						)
					)
					(width 0)
					(fill yes)
				)
			)
		)
	)
	(footprint ""
		(layer "B.Cu")
		(at 44.958 -118.364)
		(property "Reference" "TP216"
			(at 0 0 0)
			(layer "B.SilkS")
			(hide yes)
			(effects
				(font
					(size 1.27 1.27)
				)
				(justify mirror)
			)
		)
		(property "Value" "TPAD28-2-GP"
			(at 0.0127 -1.6637 0)
			(unlocked yes)
			(layer "B.Fab")
			(hide yes)
			(effects
				(font
					(size 1.016 1.016)
					(thickness 0.1524)
				)
				(justify mirror)
			)
		)
		(property "Device Type" "TPAD28"
			(at 0.0127 -3.1877 0)
			(unlocked yes)
			(layer "B.Fab")
			(hide yes)
			(effects
				(font
					(size 1.016 1.016)
					(thickness 0.1524)
				)
				(justify mirror)
			)
		)
		(duplicate_pad_numbers_are_jumpers no)
		(fp_poly
			(pts
				(arc
					(start 0.3556 0)
					(mid -0.3556 0)
					(end 0.3556 0)
				)
			)
			(stroke
				(width 0)
				(type default)
			)
			(fill no)
			(layer "B.CrtYd")
		)
		(fp_poly
			(pts
				(arc
					(start 0.6096 0)
					(mid -0.6096 0)
					(end 0.6096 0)
				)
			)
			(stroke
				(width 0)
				(type default)
			)
			(fill no)
			(layer "B.Fab")
		)
		(pad "1" smd circle
			(at 0 0 180)
			(size 0.7112 0.7112)
			(layers "B.Cu" "B.Mask" "B.Paste")
			(net "TP_GPIOA3")
		)
	)
	(footprint ""
		(layer "B.Cu")
		(at 145.761202 -64.416432 -90)
		(property "Reference" "PC197"
			(at 0 0 90)
			(layer "B.SilkS")
			(hide yes)
			(effects
				(font
					(size 1.27 1.27)
				)
				(justify mirror)
			)
		)
		(property "Value" "SC10U25V5KX-GP"
			(at 0.0762 -6.1214 270)
			(unlocked yes)
			(layer "B.Fab")
			(hide yes)
			(effects
				(font
					(size 1.016 1.016)
					(thickness 0.1524)
				)
				(justify mirror)
			)
		)
		(property "Device Type" "C805H56"
			(at 0.0762 -8.1534 270)
			(unlocked yes)
			(layer "B.Fab")
			(hide yes)
			(effects
				(font
					(size 1.016 1.016)
					(thickness 0.1524)
				)
				(justify mirror)
			)
		)
		(duplicate_pad_numbers_are_jumpers no)
		(fp_line
			(start -0.635 0)
			(end 0.635 0)
			(stroke
				(width 0.508)
				(type default)
			)
			(layer "B.SilkS")
		)
		(fp_rect
			(start 0.9652 1.778)
			(end -0.9652 -1.778)
			(stroke
				(width 0)
				(type default)
			)
			(fill no)
			(layer "B.CrtYd")
		)
		(fp_poly
			(pts
				(xy 0.9652 -1.778) (xy -0.9652 -1.778) (xy -0.9652 1.778) (xy 0.9652 1.778)
			)
			(stroke
				(width 0)
				(type default)
			)
			(fill no)
			(layer "B.Fab")
		)
		(pad "1" smd rect
			(at 0 -0.9652 90)
			(size 1.397 1.143)
			(layers "B.Cu" "B.Mask" "B.Paste")
			(net "P0V9_VIN")
		)
		(pad "2" smd rect
			(at 0 0.9652 90)
			(size 1.397 1.143)
			(layers "B.Cu" "B.Mask" "B.Paste")
			(net "GND")
		)
	)
)
